(kicad_pcb
	(version 20260206)
	(generator "pcbnew")
	(generator_version "10.0")
	(general
		(thickness 1.6)
		(legacy_teardrops no)
	)
	(paper "A4")
	(title_block
		(title "03242023_DA0F0TMBIJ0_F0T_Motherboard_J_brd_V01_OCP.brd")
		(comment 1 "Grand Teton / footprints 126-132 of 6105")
	)
	(layers
		(0 "F.Cu" signal "TOP")
		(4 "In1.Cu" signal "GND")
		(6 "In2.Cu" signal "IN1")
		(8 "In3.Cu" signal "GND1")
		(10 "In4.Cu" signal "IN2")
		(12 "In5.Cu" signal "GND2")
		(14 "In6.Cu" signal "IN3")
		(16 "In7.Cu" signal "GND3")
		(18 "In8.Cu" signal "VCC")
		(20 "In9.Cu" signal "VCC1")
		(22 "In10.Cu" signal "GND4")
		(24 "In11.Cu" signal "IN4")
		(26 "In12.Cu" signal "GND5")
		(28 "In13.Cu" signal "IN5")
		(30 "In14.Cu" signal "GND6")
		(32 "In15.Cu" signal "IN6")
		(34 "In16.Cu" signal "GND7")
		(2 "B.Cu" signal "BOTTOM")
		(9 "F.Adhes" user "F.Adhesive")
		(11 "B.Adhes" user "B.Adhesive")
		(13 "F.Paste" user "Package Geometry/Pastemask Top")
		(15 "B.Paste" user "Package Geometry/Pastemask Bottom")
		(5 "F.SilkS" user "Ref Des/Silkscreen Top")
		(7 "B.SilkS" user "Ref Des/Silkscreen Bottom")
		(1 "F.Mask" user "Board Geometry/Soldermask Top")
		(3 "B.Mask" user "Board Geometry/Soldermask Bottom")
		(17 "Dwgs.User" user "User.Drawings")
		(19 "Cmts.User" user "User.Comments")
		(21 "Eco1.User" user "User.Eco1")
		(23 "Eco2.User" user "User.Eco2")
		(25 "Edge.Cuts" user "Board Geometry/Outline")
		(27 "Margin" user)
		(31 "F.CrtYd" user "Package Geometry/Place Bound Top")
		(29 "B.CrtYd" user "Package Geometry/Place Bound Bottom")
		(35 "F.Fab" user "Ref Des/Assembly Top")
		(33 "B.Fab" user "Ref Des/Assembly Bottom")
	)
	(footprint ""
		(layer "F.Cu")
		(at 104.34193 -240.277142 90)
		(property "Reference" "C430"
			(at 0 0 90)
			(layer "F.SilkS")
			(hide yes)
			(effects
				(font
					(size 1.27 1.27)
				)
			)
		)
		(property "Value" ""
			(at 0 0 90)
			(layer "F.Fab")
			(effects
				(font
					(size 1.27 1.27)
				)
			)
		)
		(duplicate_pad_numbers_are_jumpers no)
		(fp_line
			(start 0.7874 -0.4064)
			(end 0.7874 0.4064)
			(stroke
				(width 0.1524)
				(type default)
			)
			(layer "F.SilkS")
		)
		(fp_line
			(start -0.7874 -0.4064)
			(end 0.7874 -0.4064)
			(stroke
				(width 0.1524)
				(type default)
			)
			(layer "F.SilkS")
		)
		(fp_line
			(start 0.7874 0.4064)
			(end -0.7874 0.4064)
			(stroke
				(width 0.1524)
				(type default)
			)
			(layer "F.SilkS")
		)
		(fp_line
			(start -0.7874 0.4064)
			(end -0.7874 -0.4064)
			(stroke
				(width 0.1524)
				(type default)
			)
			(layer "F.SilkS")
		)
		(fp_line
			(start -0.12065 -0.305054)
			(end -0.12065 -0.2794)
			(stroke
				(width 0.1)
				(type default)
			)
			(layer "F.Fab")
		)
		(fp_line
			(start -0.67945 -0.305054)
			(end -0.12065 -0.305054)
			(stroke
				(width 0.1)
				(type default)
			)
			(layer "F.Fab")
		)
		(fp_line
			(start 0.67945 -0.3048)
			(end 0.67945 0.3048)
			(stroke
				(width 0.1)
				(type default)
			)
			(layer "F.Fab")
		)
		(fp_line
			(start 0.12065 -0.3048)
			(end 0.67945 -0.3048)
			(stroke
				(width 0.1)
				(type default)
			)
			(layer "F.Fab")
		)
		(fp_line
			(start 0.12065 -0.2794)
			(end 0.12065 -0.3048)
			(stroke
				(width 0.1)
				(type default)
			)
			(layer "F.Fab")
		)
		(fp_line
			(start -0.12065 -0.2794)
			(end 0.12065 -0.2794)
			(stroke
				(width 0.1)
				(type default)
			)
			(layer "F.Fab")
		)
		(fp_line
			(start 0.120396 0.2794)
			(end -0.12065 0.2794)
			(stroke
				(width 0.1)
				(type default)
			)
			(layer "F.Fab")
		)
		(fp_line
			(start -0.12065 0.2794)
			(end -0.12065 0.3048)
			(stroke
				(width 0.1)
				(type default)
			)
			(layer "F.Fab")
		)
		(fp_line
			(start 0.67945 0.3048)
			(end 0.120396 0.3048)
			(stroke
				(width 0.1)
				(type default)
			)
			(layer "F.Fab")
		)
		(fp_line
			(start 0.120396 0.3048)
			(end 0.120396 0.2794)
			(stroke
				(width 0.1)
				(type default)
			)
			(layer "F.Fab")
		)
		(fp_line
			(start -0.12065 0.3048)
			(end -0.67945 0.3048)
			(stroke
				(width 0.1)
				(type default)
			)
			(layer "F.Fab")
		)
		(fp_line
			(start -0.67945 0.3048)
			(end -0.67945 -0.305054)
			(stroke
				(width 0.1)
				(type default)
			)
			(layer "F.Fab")
		)
		(pad "1" smd circle
			(at -0.40005 0 90)
			(size 0 0)
			(layers "F.Cu" "F.Mask" "F.Paste")
			(net "PVCCFA_EHV_FIVRA_CPU1")
		)
		(pad "2" smd circle
			(at 0.40005 0 90)
			(size 0 0)
			(layers "F.Cu" "F.Mask" "F.Paste")
			(net "GND")
		)
	)
	(footprint ""
		(layer "F.Cu")
		(at 374.112282 -59.295792)
		(property "Reference" "R752"
			(at 0 0 0)
			(layer "F.SilkS")
			(hide yes)
			(effects
				(font
					(size 1.27 1.27)
				)
			)
		)
		(property "Value" ""
			(at 0 0 0)
			(layer "F.Fab")
			(effects
				(font
					(size 1.27 1.27)
				)
			)
		)
		(duplicate_pad_numbers_are_jumpers no)
		(fp_line
			(start -0.7874 -0.4064)
			(end 0.7874 -0.4064)
			(stroke
				(width 0.1524)
				(type default)
			)
			(layer "F.SilkS")
		)
		(fp_line
			(start -0.7874 0.4064)
			(end -0.7874 -0.4064)
			(stroke
				(width 0.1524)
				(type default)
			)
			(layer "F.SilkS")
		)
		(fp_line
			(start 0.7874 -0.4064)
			(end 0.7874 0.4064)
			(stroke
				(width 0.1524)
				(type default)
			)
			(layer "F.SilkS")
		)
		(fp_line
			(start 0.7874 0.4064)
			(end -0.7874 0.4064)
			(stroke
				(width 0.1524)
				(type default)
			)
			(layer "F.SilkS")
		)
		(fp_line
			(start -0.67945 -0.305054)
			(end -0.12065 -0.305054)
			(stroke
				(width 0.1)
				(type default)
			)
			(layer "F.Fab")
		)
		(fp_line
			(start -0.67945 0.3048)
			(end -0.67945 -0.305054)
			(stroke
				(width 0.1)
				(type default)
			)
			(layer "F.Fab")
		)
		(fp_line
			(start -0.12065 -0.305054)
			(end -0.12065 -0.2794)
			(stroke
				(width 0.1)
				(type default)
			)
			(layer "F.Fab")
		)
		(fp_line
			(start -0.12065 -0.2794)
			(end 0.12065 -0.2794)
			(stroke
				(width 0.1)
				(type default)
			)
			(layer "F.Fab")
		)
		(fp_line
			(start -0.12065 0.2794)
			(end -0.12065 0.3048)
			(stroke
				(width 0.1)
				(type default)
			)
			(layer "F.Fab")
		)
		(fp_line
			(start -0.12065 0.3048)
			(end -0.67945 0.3048)
			(stroke
				(width 0.1)
				(type default)
			)
			(layer "F.Fab")
		)
		(fp_line
			(start 0.120396 0.2794)
			(end -0.12065 0.2794)
			(stroke
				(width 0.1)
				(type default)
			)
			(layer "F.Fab")
		)
		(fp_line
			(start 0.120396 0.3048)
			(end 0.120396 0.2794)
			(stroke
				(width 0.1)
				(type default)
			)
			(layer "F.Fab")
		)
		(fp_line
			(start 0.12065 -0.3048)
			(end 0.67945 -0.3048)
			(stroke
				(width 0.1)
				(type default)
			)
			(layer "F.Fab")
		)
		(fp_line
			(start 0.12065 -0.2794)
			(end 0.12065 -0.3048)
			(stroke
				(width 0.1)
				(type default)
			)
			(layer "F.Fab")
		)
		(fp_line
			(start 0.67945 -0.3048)
			(end 0.67945 0.3048)
			(stroke
				(width 0.1)
				(type default)
			)
			(layer "F.Fab")
		)
		(fp_line
			(start 0.67945 0.3048)
			(end 0.120396 0.3048)
			(stroke
				(width 0.1)
				(type default)
			)
			(layer "F.Fab")
		)
		(pad "1" smd circle
			(at -0.40005 0)
			(size 0 0)
			(layers "F.Cu" "F.Mask" "F.Paste")
			(net "JTAG_DBP_TDO")
		)
		(pad "2" smd circle
			(at 0.40005 0)
			(size 0 0)
			(layers "F.Cu" "F.Mask" "F.Paste")
			(net "JTAG_DBP_TDO_PCH")
		)
	)
	(footprint ""
		(layer "F.Cu")
		(at 313.53506 -26.062432 180)
		(property "Reference" "R1545"
			(at 0 0 180)
			(layer "F.SilkS")
			(hide yes)
			(effects
				(font
					(size 1.27 1.27)
				)
			)
		)
		(property "Value" ""
			(at 0 0 180)
			(layer "F.Fab")
			(effects
				(font
					(size 1.27 1.27)
				)
			)
		)
		(duplicate_pad_numbers_are_jumpers no)
		(fp_line
			(start 0.7874 0.4064)
			(end -0.7874 0.4064)
			(stroke
				(width 0.1524)
				(type default)
			)
			(layer "F.SilkS")
		)
		(fp_line
			(start 0.7874 -0.4064)
			(end 0.7874 0.4064)
			(stroke
				(width 0.1524)
				(type default)
			)
			(layer "F.SilkS")
		)
		(fp_line
			(start -0.7874 0.4064)
			(end -0.7874 -0.4064)
			(stroke
				(width 0.1524)
				(type default)
			)
			(layer "F.SilkS")
		)
		(fp_line
			(start -0.7874 -0.4064)
			(end 0.7874 -0.4064)
			(stroke
				(width 0.1524)
				(type default)
			)
			(layer "F.SilkS")
		)
		(fp_line
			(start 0.67945 0.3048)
			(end 0.120396 0.3048)
			(stroke
				(width 0.1)
				(type default)
			)
			(layer "F.Fab")
		)
		(fp_line
			(start 0.67945 -0.3048)
			(end 0.67945 0.3048)
			(stroke
				(width 0.1)
				(type default)
			)
			(layer "F.Fab")
		)
		(fp_line
			(start 0.12065 -0.2794)
			(end 0.12065 -0.3048)
			(stroke
				(width 0.1)
				(type default)
			)
			(layer "F.Fab")
		)
		(fp_line
			(start 0.12065 -0.3048)
			(end 0.67945 -0.3048)
			(stroke
				(width 0.1)
				(type default)
			)
			(layer "F.Fab")
		)
		(fp_line
			(start 0.120396 0.3048)
			(end 0.120396 0.2794)
			(stroke
				(width 0.1)
				(type default)
			)
			(layer "F.Fab")
		)
		(fp_line
			(start 0.120396 0.2794)
			(end -0.12065 0.2794)
			(stroke
				(width 0.1)
				(type default)
			)
			(layer "F.Fab")
		)
		(fp_line
			(start -0.12065 0.3048)
			(end -0.67945 0.3048)
			(stroke
				(width 0.1)
				(type default)
			)
			(layer "F.Fab")
		)
		(fp_line
			(start -0.12065 0.2794)
			(end -0.12065 0.3048)
			(stroke
				(width 0.1)
				(type default)
			)
			(layer "F.Fab")
		)
		(fp_line
			(start -0.12065 -0.2794)
			(end 0.12065 -0.2794)
			(stroke
				(width 0.1)
				(type default)
			)
			(layer "F.Fab")
		)
		(fp_line
			(start -0.12065 -0.305054)
			(end -0.12065 -0.2794)
			(stroke
				(width 0.1)
				(type default)
			)
			(layer "F.Fab")
		)
		(fp_line
			(start -0.67945 0.3048)
			(end -0.67945 -0.305054)
			(stroke
				(width 0.1)
				(type default)
			)
			(layer "F.Fab")
		)
		(fp_line
			(start -0.67945 -0.305054)
			(end -0.12065 -0.305054)
			(stroke
				(width 0.1)
				(type default)
			)
			(layer "F.Fab")
		)
		(pad "1" smd circle
			(at -0.40005 0 180)
			(size 0 0)
			(layers "F.Cu" "F.Mask" "F.Paste")
			(net "SMB_SML0B_3V3AUX_SCL")
		)
		(pad "2" smd circle
			(at 0.40005 0 180)
			(size 0 0)
			(layers "F.Cu" "F.Mask" "F.Paste")
			(net "P3V3_AUX")
		)
	)
	(footprint ""
		(layer "F.Cu")
		(at 164.64788 -112.232948)
		(property "Reference" "R3477"
			(at 0 0 0)
			(layer "F.SilkS")
			(hide yes)
			(effects
				(font
					(size 1.27 1.27)
				)
			)
		)
		(property "Value" ""
			(at 0 0 0)
			(layer "F.Fab")
			(effects
				(font
					(size 1.27 1.27)
				)
			)
		)
		(duplicate_pad_numbers_are_jumpers no)
		(fp_line
			(start -0.7874 -0.4064)
			(end 0.7874 -0.4064)
			(stroke
				(width 0.1524)
				(type default)
			)
			(layer "F.SilkS")
		)
		(fp_line
			(start -0.7874 0.4064)
			(end -0.7874 -0.4064)
			(stroke
				(width 0.1524)
				(type default)
			)
			(layer "F.SilkS")
		)
		(fp_line
			(start 0.7874 -0.4064)
			(end 0.7874 0.4064)
			(stroke
				(width 0.1524)
				(type default)
			)
			(layer "F.SilkS")
		)
		(fp_line
			(start 0.7874 0.4064)
			(end -0.7874 0.4064)
			(stroke
				(width 0.1524)
				(type default)
			)
			(layer "F.SilkS")
		)
		(fp_line
			(start -0.67945 -0.305054)
			(end -0.12065 -0.305054)
			(stroke
				(width 0.1)
				(type default)
			)
			(layer "F.Fab")
		)
		(fp_line
			(start -0.67945 0.3048)
			(end -0.67945 -0.305054)
			(stroke
				(width 0.1)
				(type default)
			)
			(layer "F.Fab")
		)
		(fp_line
			(start -0.12065 -0.305054)
			(end -0.12065 -0.2794)
			(stroke
				(width 0.1)
				(type default)
			)
			(layer "F.Fab")
		)
		(fp_line
			(start -0.12065 -0.2794)
			(end 0.12065 -0.2794)
			(stroke
				(width 0.1)
				(type default)
			)
			(layer "F.Fab")
		)
		(fp_line
			(start -0.12065 0.2794)
			(end -0.12065 0.3048)
			(stroke
				(width 0.1)
				(type default)
			)
			(layer "F.Fab")
		)
		(fp_line
			(start -0.12065 0.3048)
			(end -0.67945 0.3048)
			(stroke
				(width 0.1)
				(type default)
			)
			(layer "F.Fab")
		)
		(fp_line
			(start 0.120396 0.2794)
			(end -0.12065 0.2794)
			(stroke
				(width 0.1)
				(type default)
			)
			(layer "F.Fab")
		)
		(fp_line
			(start 0.120396 0.3048)
			(end 0.120396 0.2794)
			(stroke
				(width 0.1)
				(type default)
			)
			(layer "F.Fab")
		)
		(fp_line
			(start 0.12065 -0.3048)
			(end 0.67945 -0.3048)
			(stroke
				(width 0.1)
				(type default)
			)
			(layer "F.Fab")
		)
		(fp_line
			(start 0.12065 -0.2794)
			(end 0.12065 -0.3048)
			(stroke
				(width 0.1)
				(type default)
			)
			(layer "F.Fab")
		)
		(fp_line
			(start 0.67945 -0.3048)
			(end 0.67945 0.3048)
			(stroke
				(width 0.1)
				(type default)
			)
			(layer "F.Fab")
		)
		(fp_line
			(start 0.67945 0.3048)
			(end 0.120396 0.3048)
			(stroke
				(width 0.1)
				(type default)
			)
			(layer "F.Fab")
		)
		(pad "1" smd circle
			(at -0.40005 0)
			(size 0 0)
			(layers "F.Cu" "F.Mask" "F.Paste")
			(net "GPU_NVS_PWR_BRAKE_N")
		)
		(pad "2" smd circle
			(at 0.40005 0)
			(size 0 0)
			(layers "F.Cu" "F.Mask" "F.Paste")
			(net "GPU_NVS_PWR_BRAKE_R_N")
		)
	)
	(footprint ""
		(layer "F.Cu")
		(at 323.680328 -408.517344 -90)
		(property "Reference" "C914"
			(at 0 0 270)
			(layer "F.SilkS")
			(hide yes)
			(effects
				(font
					(size 1.27 1.27)
				)
			)
		)
		(property "Value" ""
			(at 0 0 270)
			(layer "F.Fab")
			(effects
				(font
					(size 1.27 1.27)
				)
			)
		)
		(duplicate_pad_numbers_are_jumpers no)
		(fp_line
			(start -0.299974 0.150114)
			(end -0.299974 -0.150114)
			(stroke
				(width 0.1)
				(type default)
			)
			(layer "F.Fab")
		)
		(fp_line
			(start 0.299974 0.150114)
			(end -0.299974 0.150114)
			(stroke
				(width 0.1)
				(type default)
			)
			(layer "F.Fab")
		)
		(fp_line
			(start -0.299974 -0.150114)
			(end 0.299974 -0.150114)
			(stroke
				(width 0.1)
				(type default)
			)
			(layer "F.Fab")
		)
		(fp_line
			(start 0.299974 -0.150114)
			(end 0.299974 0.150114)
			(stroke
				(width 0.1)
				(type default)
			)
			(layer "F.Fab")
		)
		(pad "1" smd rect
			(at -0.2667 0 270)
			(size 0.3048 0.381)
			(layers "F.Cu" "F.Mask" "F.Paste")
			(net "P5E_CPU0_PE0_TX_C_DN<9>")
		)
		(pad "2" smd rect
			(at 0.2667 0 270)
			(size 0.3048 0.381)
			(layers "F.Cu" "F.Mask" "F.Paste")
			(net "P5E_CPU0_PE0_TX_DN<9>")
		)
	)
	(footprint ""
		(layer "F.Cu")
		(at 101.833934 -395.42974)
		(property "Reference" "R3492"
			(at 0 0 0)
			(layer "F.SilkS")
			(hide yes)
			(effects
				(font
					(size 1.27 1.27)
				)
			)
		)
		(property "Value" ""
			(at 0 0 0)
			(layer "F.Fab")
			(effects
				(font
					(size 1.27 1.27)
				)
			)
		)
		(duplicate_pad_numbers_are_jumpers no)
		(fp_line
			(start -0.7874 -0.4064)
			(end 0.7874 -0.4064)
			(stroke
				(width 0.1524)
				(type default)
			)
			(layer "F.SilkS")
		)
		(fp_line
			(start -0.7874 0.4064)
			(end -0.7874 -0.4064)
			(stroke
				(width 0.1524)
				(type default)
			)
			(layer "F.SilkS")
		)
		(fp_line
			(start 0.7874 -0.4064)
			(end 0.7874 0.4064)
			(stroke
				(width 0.1524)
				(type default)
			)
			(layer "F.SilkS")
		)
		(fp_line
			(start 0.7874 0.4064)
			(end -0.7874 0.4064)
			(stroke
				(width 0.1524)
				(type default)
			)
			(layer "F.SilkS")
		)
		(fp_line
			(start -0.67945 -0.305054)
			(end -0.12065 -0.305054)
			(stroke
				(width 0.1)
				(type default)
			)
			(layer "F.Fab")
		)
		(fp_line
			(start -0.67945 0.3048)
			(end -0.67945 -0.305054)
			(stroke
				(width 0.1)
				(type default)
			)
			(layer "F.Fab")
		)
		(fp_line
			(start -0.12065 -0.305054)
			(end -0.12065 -0.2794)
			(stroke
				(width 0.1)
				(type default)
			)
			(layer "F.Fab")
		)
		(fp_line
			(start -0.12065 -0.2794)
			(end 0.12065 -0.2794)
			(stroke
				(width 0.1)
				(type default)
			)
			(layer "F.Fab")
		)
		(fp_line
			(start -0.12065 0.2794)
			(end -0.12065 0.3048)
			(stroke
				(width 0.1)
				(type default)
			)
			(layer "F.Fab")
		)
		(fp_line
			(start -0.12065 0.3048)
			(end -0.67945 0.3048)
			(stroke
				(width 0.1)
				(type default)
			)
			(layer "F.Fab")
		)
		(fp_line
			(start 0.120396 0.2794)
			(end -0.12065 0.2794)
			(stroke
				(width 0.1)
				(type default)
			)
			(layer "F.Fab")
		)
		(fp_line
			(start 0.120396 0.3048)
			(end 0.120396 0.2794)
			(stroke
				(width 0.1)
				(type default)
			)
			(layer "F.Fab")
		)
		(fp_line
			(start 0.12065 -0.3048)
			(end 0.67945 -0.3048)
			(stroke
				(width 0.1)
				(type default)
			)
			(layer "F.Fab")
		)
		(fp_line
			(start 0.12065 -0.2794)
			(end 0.12065 -0.3048)
			(stroke
				(width 0.1)
				(type default)
			)
			(layer "F.Fab")
		)
		(fp_line
			(start 0.67945 -0.3048)
			(end 0.67945 0.3048)
			(stroke
				(width 0.1)
				(type default)
			)
			(layer "F.Fab")
		)
		(fp_line
			(start 0.67945 0.3048)
			(end 0.120396 0.3048)
			(stroke
				(width 0.1)
				(type default)
			)
			(layer "F.Fab")
		)
		(pad "1" smd circle
			(at -0.40005 0)
			(size 0 0)
			(layers "F.Cu" "F.Mask" "F.Paste")
			(net "P3V3_AUX")
		)
		(pad "2" smd circle
			(at 0.40005 0)
			(size 0 0)
			(layers "F.Cu" "F.Mask" "F.Paste")
			(net "GPU_FPGA_EROT_RST_BUF_R_N")
		)
	)
	(footprint ""
		(layer "F.Cu")
		(at 19.769582 -428.024036 90)
		(property "Reference" "R3441"
			(at 0 0 90)
			(layer "F.SilkS")
			(hide yes)
			(effects
				(font
					(size 1.27 1.27)
				)
			)
		)
		(property "Value" ""
			(at 0 0 90)
			(layer "F.Fab")
			(effects
				(font
					(size 1.27 1.27)
				)
			)
		)
		(duplicate_pad_numbers_are_jumpers no)
		(fp_line
			(start 0.7874 -0.4064)
			(end 0.7874 0.4064)
			(stroke
				(width 0.1524)
				(type default)
			)
			(layer "F.SilkS")
		)
		(fp_line
			(start -0.7874 -0.4064)
			(end 0.7874 -0.4064)
			(stroke
				(width 0.1524)
				(type default)
			)
			(layer "F.SilkS")
		)
		(fp_line
			(start 0.7874 0.4064)
			(end -0.7874 0.4064)
			(stroke
				(width 0.1524)
				(type default)
			)
			(layer "F.SilkS")
		)
		(fp_line
			(start -0.7874 0.4064)
			(end -0.7874 -0.4064)
			(stroke
				(width 0.1524)
				(type default)
			)
			(layer "F.SilkS")
		)
		(fp_line
			(start -0.12065 -0.305054)
			(end -0.12065 -0.2794)
			(stroke
				(width 0.1)
				(type default)
			)
			(layer "F.Fab")
		)
		(fp_line
			(start -0.67945 -0.305054)
			(end -0.12065 -0.305054)
			(stroke
				(width 0.1)
				(type default)
			)
			(layer "F.Fab")
		)
		(fp_line
			(start 0.67945 -0.3048)
			(end 0.67945 0.3048)
			(stroke
				(width 0.1)
				(type default)
			)
			(layer "F.Fab")
		)
		(fp_line
			(start 0.12065 -0.3048)
			(end 0.67945 -0.3048)
			(stroke
				(width 0.1)
				(type default)
			)
			(layer "F.Fab")
		)
		(fp_line
			(start 0.12065 -0.2794)
			(end 0.12065 -0.3048)
			(stroke
				(width 0.1)
				(type default)
			)
			(layer "F.Fab")
		)
		(fp_line
			(start -0.12065 -0.2794)
			(end 0.12065 -0.2794)
			(stroke
				(width 0.1)
				(type default)
			)
			(layer "F.Fab")
		)
		(fp_line
			(start 0.120396 0.2794)
			(end -0.12065 0.2794)
			(stroke
				(width 0.1)
				(type default)
			)
			(layer "F.Fab")
		)
		(fp_line
			(start -0.12065 0.2794)
			(end -0.12065 0.3048)
			(stroke
				(width 0.1)
				(type default)
			)
			(layer "F.Fab")
		)
		(fp_line
			(start 0.67945 0.3048)
			(end 0.120396 0.3048)
			(stroke
				(width 0.1)
				(type default)
			)
			(layer "F.Fab")
		)
		(fp_line
			(start 0.120396 0.3048)
			(end 0.120396 0.2794)
			(stroke
				(width 0.1)
				(type default)
			)
			(layer "F.Fab")
		)
		(fp_line
			(start -0.12065 0.3048)
			(end -0.67945 0.3048)
			(stroke
				(width 0.1)
				(type default)
			)
			(layer "F.Fab")
		)
		(fp_line
			(start -0.67945 0.3048)
			(end -0.67945 -0.305054)
			(stroke
				(width 0.1)
				(type default)
			)
			(layer "F.Fab")
		)
		(pad "1" smd circle
			(at -0.40005 0 90)
			(size 0 0)
			(layers "F.Cu" "F.Mask" "F.Paste")
			(net "GPU_BASE_ID1")
		)
		(pad "2" smd circle
			(at 0.40005 0 90)
			(size 0 0)
			(layers "F.Cu" "F.Mask" "F.Paste")
			(net "GND")
		)
	)
)
